(kicad_pcb
	(version 20260206)
	(generator "pcbnew")
	(generator_version "10.0")
	(general
		(thickness 1.21888)
		(legacy_teardrops no)
	)
	(paper "A4")
	(title_block
		(title "timecard-v8 — TimeCard-DC-V8_EXP.PcbDoc")
		(comment 1 "Time Appliance Project (Time Card) / footprints 110-113 of 288")
	)
	(layers
		(0 "F.Cu" signal "TOP")
		(4 "In1.Cu" signal "SGND")
		(6 "In2.Cu" signal "IN1")
		(8 "In3.Cu" signal "IN2")
		(10 "In4.Cu" signal "SGND1")
		(2 "B.Cu" signal "BOTTOM")
		(9 "F.Adhes" user "F.Adhesive")
		(11 "B.Adhes" user "B.Adhesive")
		(13 "F.Paste" user "Top Paste")
		(15 "B.Paste" user "Bottom Paste")
		(5 "F.SilkS" user "Top Overlay")
		(7 "B.SilkS" user "Bottom Overlay")
		(1 "F.Mask" user "Top Solder")
		(3 "B.Mask" user "Bottom Solder")
		(17 "Dwgs.User" user "User.Drawings")
		(19 "Cmts.User" user "User.Comments")
		(21 "Eco1.User" user "User.Eco1")
		(23 "Eco2.User" user "User.Eco2")
		(25 "Edge.Cuts" user)
		(27 "Margin" user)
		(31 "F.CrtYd" user "Top Courtyard")
		(29 "B.CrtYd" user "Bottom Courtyard")
		(35 "F.Fab" user "Top Component Center")
		(33 "B.Fab" user "Bottom Component Center")
	)
	(footprint "FPGA_CONN:SingleFPGAConn"
		(layer "F.Cu")
		(at 149.7158 124.56234)
		(property "Reference" "J36"
			(at -0.39436 -23.455129 0)
			(unlocked yes)
			(layer "F.SilkS")
			(effects
				(font
					(size 0.762 0.762)
					(thickness 0.2286)
				)
			)
		)
		(property "Value" "Single FPGA Conn"
			(at 9.25452 3.621231 0)
			(unlocked yes)
			(layer "F.SilkS")
			(hide yes)
			(effects
				(font
					(size 0.762 0.762)
					(thickness 0.2286)
				)
			)
		)
		(sheetname "FPGA")
		(sheetfile "FPGA.kicad_sch")
		(duplicate_pad_numbers_are_jumpers no)
		(fp_line
			(start -1.99999 -20.69998)
			(end -1.40005 -20.69998)
			(stroke
				(width 0.15011)
				(type solid)
			)
			(layer "F.SilkS")
		)
		(fp_line
			(start -1.99999 -20.03298)
			(end -1.99999 -20.69998)
			(stroke
				(width 0.15011)
				(type solid)
			)
			(layer "F.SilkS")
		)
		(fp_line
			(start -1.99999 0.70003)
			(end -1.99999 0.03302)
			(stroke
				(width 0.15011)
				(type solid)
			)
			(layer "F.SilkS")
		)
		(fp_line
			(start -1.99999 0.70003)
			(end -1.40005 0.70003)
			(stroke
				(width 0.15011)
				(type solid)
			)
			(layer "F.SilkS")
		)
		(fp_line
			(start -1.40005 -21.24989)
			(end 1.40005 -21.24989)
			(stroke
				(width 0.15011)
				(type solid)
			)
			(layer "F.SilkS")
		)
		(fp_line
			(start -1.40005 -20.69998)
			(end -1.40005 -21.24989)
			(stroke
				(width 0.15011)
				(type solid)
			)
			(layer "F.SilkS")
		)
		(fp_line
			(start -1.40005 1.24994)
			(end -1.40005 0.70003)
			(stroke
				(width 0.15011)
				(type solid)
			)
			(layer "F.SilkS")
		)
		(fp_line
			(start -1.40005 1.24994)
			(end 1.40005 1.24994)
			(stroke
				(width 0.15011)
				(type solid)
			)
			(layer "F.SilkS")
		)
		(fp_line
			(start 1.40005 -21.24989)
			(end 2 -20.69998)
			(stroke
				(width 0.15011)
				(type solid)
			)
			(layer "F.SilkS")
		)
		(fp_line
			(start 1.40005 1.24994)
			(end 2 0.70003)
			(stroke
				(width 0.15011)
				(type solid)
			)
			(layer "F.SilkS")
		)
		(fp_line
			(start 2 -20.03298)
			(end 2 -20.69998)
			(stroke
				(width 0.15011)
				(type solid)
			)
			(layer "F.SilkS")
		)
		(fp_line
			(start 2 0.70003)
			(end 2 0.03302)
			(stroke
				(width 0.15011)
				(type solid)
			)
			(layer "F.SilkS")
		)
		(fp_circle
			(center 3.5052 -0.22453)
			(end 3.5052 -0.42468)
			(stroke
				(width 0.40005)
				(type solid)
			)
			(fill no)
			(layer "F.SilkS")
		)
		(pad "1" smd rect
			(at 2.02489 -0.24993)
			(size 1.54991 0.24994)
			(layers "F.Cu" "F.Mask" "F.Paste")
			(net "GPS2_TX_FPGA")
		)
		(pad "2" smd rect
			(at -2.02489 -0.24993)
			(size 1.54991 0.24994)
			(layers "F.Cu" "F.Mask" "F.Paste")
			(net "GPS2_RX_FPGA")
		)
		(pad "3" smd rect
			(at 2.02489 -0.75006)
			(size 1.54991 0.24994)
			(layers "F.Cu" "F.Mask" "F.Paste")
		)
		(pad "4" smd rect
			(at -2.02489 -0.75006)
			(size 1.54991 0.24994)
			(layers "F.Cu" "F.Mask" "F.Paste")
		)
		(pad "5" smd rect
			(at 2.02489 -1.24993)
			(size 1.54991 0.24994)
			(layers "F.Cu" "F.Mask" "F.Paste")
			(net "GPS2_TP1")
		)
		(pad "6" smd rect
			(at -2.02489 -1.24993)
			(size 1.54991 0.24994)
			(layers "F.Cu" "F.Mask" "F.Paste")
		)
		(pad "7" smd rect
			(at 2.02489 -1.75006)
			(size 1.54991 0.24994)
			(layers "F.Cu" "F.Mask" "F.Paste")
			(net "GPS2_TP2")
		)
		(pad "8" smd rect
			(at -2.02489 -1.75006)
			(size 1.54991 0.24994)
			(layers "F.Cu" "F.Mask" "F.Paste")
		)
		(pad "9" smd rect
			(at 2.02489 -2.24993)
			(size 1.54991 0.24994)
			(layers "F.Cu" "F.Mask" "F.Paste")
			(net "GND")
		)
		(pad "10" smd rect
			(at -2.02489 -2.24993)
			(size 1.54991 0.24994)
			(layers "F.Cu" "F.Mask" "F.Paste")
			(net "GND")
		)
		(pad "11" smd rect
			(at 2.02489 -2.75006)
			(size 1.54991 0.24994)
			(layers "F.Cu" "F.Mask" "F.Paste")
			(net "GPS2_RST")
		)
		(pad "12" smd rect
			(at -2.02489 -2.75006)
			(size 1.54991 0.24994)
			(layers "F.Cu" "F.Mask" "F.Paste")
			(net "IO_LED1")
		)
		(pad "13" smd rect
			(at 2.02489 -3.24993)
			(size 1.54991 0.24994)
			(layers "F.Cu" "F.Mask" "F.Paste")
		)
		(pad "14" smd rect
			(at -2.02489 -3.24993)
			(size 1.54991 0.24994)
			(layers "F.Cu" "F.Mask" "F.Paste")
			(net "IO_LED2")
		)
		(pad "15" smd rect
			(at 2.02489 -3.75005)
			(size 1.54991 0.24994)
			(layers "F.Cu" "F.Mask" "F.Paste")
		)
		(pad "16" smd rect
			(at -2.02489 -3.75005)
			(size 1.54991 0.24994)
			(layers "F.Cu" "F.Mask" "F.Paste")
			(net "IO_LED3")
		)
		(pad "17" smd rect
			(at 2.02489 -4.24993)
			(size 1.54991 0.24994)
			(layers "F.Cu" "F.Mask" "F.Paste")
		)
		(pad "18" smd rect
			(at -2.02489 -4.24993)
			(size 1.54991 0.24994)
			(layers "F.Cu" "F.Mask" "F.Paste")
			(net "IO_LED4")
		)
		(pad "19" smd rect
			(at 2.02489 -4.75005)
			(size 1.54991 0.24994)
			(layers "F.Cu" "F.Mask" "F.Paste")
			(net "GND")
		)
		(pad "20" smd rect
			(at -2.02489 -4.75005)
			(size 1.54991 0.24994)
			(layers "F.Cu" "F.Mask" "F.Paste")
			(net "GND")
		)
		(pad "21" smd rect
			(at 2.02489 -5.24992)
			(size 1.54991 0.24994)
			(layers "F.Cu" "F.Mask" "F.Paste")
			(net "PCIE_PERST")
		)
		(pad "22" smd rect
			(at -2.02489 -5.24992)
			(size 1.54991 0.24994)
			(layers "F.Cu" "F.Mask" "F.Paste")
		)
		(pad "23" smd rect
			(at 2.02489 -5.75005)
			(size 1.54991 0.24994)
			(layers "F.Cu" "F.Mask" "F.Paste")
			(net "KEY1")
		)
		(pad "24" smd rect
			(at -2.02489 -5.75005)
			(size 1.54991 0.24994)
			(layers "F.Cu" "F.Mask" "F.Paste")
		)
		(pad "25" smd rect
			(at 2.02489 -6.24992)
			(size 1.54991 0.24994)
			(layers "F.Cu" "F.Mask" "F.Paste")
		)
		(pad "26" smd rect
			(at -2.02489 -6.24992)
			(size 1.54991 0.24994)
			(layers "F.Cu" "F.Mask" "F.Paste")
		)
		(pad "27" smd rect
			(at 2.02489 -6.75005)
			(size 1.54991 0.24994)
			(layers "F.Cu" "F.Mask" "F.Paste")
		)
		(pad "28" smd rect
			(at -2.02489 -6.75005)
			(size 1.54991 0.24994)
			(layers "F.Cu" "F.Mask" "F.Paste")
		)
		(pad "29" smd rect
			(at 2.02489 -7.24992)
			(size 1.54991 0.24994)
			(layers "F.Cu" "F.Mask" "F.Paste")
			(net "GND")
		)
		(pad "30" smd rect
			(at -2.02489 -7.24992)
			(size 1.54991 0.24994)
			(layers "F.Cu" "F.Mask" "F.Paste")
			(net "GND")
		)
		(pad "31" smd rect
			(at 2.02489 -7.75005)
			(size 1.54991 0.24994)
			(layers "F.Cu" "F.Mask" "F.Paste")
			(net "ANT1_IO_OUT")
		)
		(pad "32" smd rect
			(at -2.02489 -7.75005)
			(size 1.54991 0.24994)
			(layers "F.Cu" "F.Mask" "F.Paste")
			(net "EXT_GPIO_7")
		)
		(pad "33" smd rect
			(at 2.02489 -8.24992)
			(size 1.54991 0.24994)
			(layers "F.Cu" "F.Mask" "F.Paste")
			(net "ANT1_IO_IN")
		)
		(pad "34" smd rect
			(at -2.02489 -8.24992)
			(size 1.54991 0.24994)
			(layers "F.Cu" "F.Mask" "F.Paste")
			(net "EXT_GPIO_8")
		)
		(pad "35" smd rect
			(at 2.02489 -8.75004)
			(size 1.54991 0.24994)
			(layers "F.Cu" "F.Mask" "F.Paste")
			(net "ANT2_IO_OUT")
		)
		(pad "36" smd rect
			(at -2.02489 -8.75004)
			(size 1.54991 0.24994)
			(layers "F.Cu" "F.Mask" "F.Paste")
			(net "EXT_GPIO_9")
		)
		(pad "37" smd rect
			(at 2.02489 -9.24992)
			(size 1.54991 0.24994)
			(layers "F.Cu" "F.Mask" "F.Paste")
			(net "ANT2_IO_IN")
		)
		(pad "38" smd rect
			(at -2.02489 -9.24992)
			(size 1.54991 0.24994)
			(layers "F.Cu" "F.Mask" "F.Paste")
			(net "EXT_GPIO_10")
		)
		(pad "39" smd rect
			(at 2.02489 -9.75004)
			(size 1.54991 0.24994)
			(layers "F.Cu" "F.Mask" "F.Paste")
			(net "GND")
		)
		(pad "40" smd rect
			(at -2.02489 -9.75004)
			(size 1.54991 0.24994)
			(layers "F.Cu" "F.Mask" "F.Paste")
			(net "GND")
		)
		(pad "41" smd rect
			(at 2.02489 -10.24991)
			(size 1.54991 0.24994)
			(layers "F.Cu" "F.Mask" "F.Paste")
			(net "ANT3_IO_OUT")
		)
		(pad "42" smd rect
			(at -2.02489 -10.24991)
			(size 1.54991 0.24994)
			(layers "F.Cu" "F.Mask" "F.Paste")
			(net "EXT_GPIO_1")
		)
		(pad "43" smd rect
			(at 2.02489 -10.75004)
			(size 1.54991 0.24994)
			(layers "F.Cu" "F.Mask" "F.Paste")
			(net "ANT3_IO_IN")
		)
		(pad "44" smd rect
			(at -2.02489 -10.75004)
			(size 1.54991 0.24994)
			(layers "F.Cu" "F.Mask" "F.Paste")
			(net "EXT_GPIO_2")
		)
		(pad "45" smd rect
			(at 2.02489 -11.24991)
			(size 1.54991 0.24994)
			(layers "F.Cu" "F.Mask" "F.Paste")
			(net "ANT4_IO_OUT")
		)
		(pad "46" smd rect
			(at -2.02489 -11.24991)
			(size 1.54991 0.24994)
			(layers "F.Cu" "F.Mask" "F.Paste")
			(net "EXT_GPIO_3")
		)
		(pad "47" smd rect
			(at 2.02489 -11.75004)
			(size 1.54991 0.24994)
			(layers "F.Cu" "F.Mask" "F.Paste")
			(net "ANT4_IO_IN")
		)
		(pad "48" smd rect
			(at -2.02489 -11.75004)
			(size 1.54991 0.24994)
			(layers "F.Cu" "F.Mask" "F.Paste")
			(net "EXT_GPIO_4")
		)
		(pad "49" smd rect
			(at 2.02489 -12.24991)
			(size 1.54991 0.24994)
			(layers "F.Cu" "F.Mask" "F.Paste")
			(net "GND")
		)
		(pad "50" smd rect
			(at -2.02489 -12.24991)
			(size 1.54991 0.24994)
			(layers "F.Cu" "F.Mask" "F.Paste")
			(net "GND")
		)
		(pad "51" smd rect
			(at 2.02489 -12.75004)
			(size 1.54991 0.24994)
			(layers "F.Cu" "F.Mask" "F.Paste")
		)
		(pad "52" smd rect
			(at -2.02489 -12.75004)
			(size 1.54991 0.24994)
			(layers "F.Cu" "F.Mask" "F.Paste")
		)
		(pad "53" smd rect
			(at 2.02489 -13.24991)
			(size 1.54991 0.24994)
			(layers "F.Cu" "F.Mask" "F.Paste")
		)
		(pad "54" smd rect
			(at -2.02489 -13.24991)
			(size 1.54991 0.24994)
			(layers "F.Cu" "F.Mask" "F.Paste")
		)
		(pad "55" smd rect
			(at 2.02489 -13.75003)
			(size 1.54991 0.24994)
			(layers "F.Cu" "F.Mask" "F.Paste")
		)
		(pad "56" smd rect
			(at -2.02489 -13.75003)
			(size 1.54991 0.24994)
			(layers "F.Cu" "F.Mask" "F.Paste")
		)
		(pad "57" smd rect
			(at 2.02489 -14.24991)
			(size 1.54991 0.24994)
			(layers "F.Cu" "F.Mask" "F.Paste")
		)
		(pad "58" smd rect
			(at -2.02489 -14.24991)
			(size 1.54991 0.24994)
			(layers "F.Cu" "F.Mask" "F.Paste")
		)
		(pad "59" smd rect
			(at 2.02489 -14.75003)
			(size 1.54991 0.24994)
			(layers "F.Cu" "F.Mask" "F.Paste")
			(net "GND")
		)
		(pad "60" smd rect
			(at -2.02489 -14.75003)
			(size 1.54991 0.24994)
			(layers "F.Cu" "F.Mask" "F.Paste")
			(net "GND")
		)
		(pad "61" smd rect
			(at 2.02489 -15.2499)
			(size 1.54991 0.24994)
			(layers "F.Cu" "F.Mask" "F.Paste")
		)
		(pad "62" smd rect
			(at -2.02489 -15.2499)
			(size 1.54991 0.24994)
			(layers "F.Cu" "F.Mask" "F.Paste")
		)
		(pad "63" smd rect
			(at 2.02489 -15.75003)
			(size 1.54991 0.24994)
			(layers "F.Cu" "F.Mask" "F.Paste")
		)
		(pad "64" smd rect
			(at -2.02489 -15.75003)
			(size 1.54991 0.24994)
			(layers "F.Cu" "F.Mask" "F.Paste")
		)
		(pad "65" smd rect
			(at 2.02489 -16.2499)
			(size 1.54991 0.24994)
			(layers "F.Cu" "F.Mask" "F.Paste")
		)
		(pad "66" smd rect
			(at -2.02489 -16.2499)
			(size 1.54991 0.24994)
			(layers "F.Cu" "F.Mask" "F.Paste")
		)
		(pad "67" smd rect
			(at 2.02489 -16.75003)
			(size 1.54991 0.24994)
			(layers "F.Cu" "F.Mask" "F.Paste")
		)
		(pad "68" smd rect
			(at -2.02489 -16.75003)
			(size 1.54991 0.24994)
			(layers "F.Cu" "F.Mask" "F.Paste")
		)
		(pad "69" smd rect
			(at 2.02489 -17.2499)
			(size 1.54991 0.24994)
			(layers "F.Cu" "F.Mask" "F.Paste")
			(net "GND")
		)
		(pad "70" smd rect
			(at -2.02489 -17.2499)
			(size 1.54991 0.24994)
			(layers "F.Cu" "F.Mask" "F.Paste")
			(net "GND")
		)
		(pad "71" smd rect
			(at 2.02489 -17.75003)
			(size 1.54991 0.24994)
			(layers "F.Cu" "F.Mask" "F.Paste")
		)
		(pad "72" smd rect
			(at -2.02489 -17.75003)
			(size 1.54991 0.24994)
			(layers "F.Cu" "F.Mask" "F.Paste")
		)
		(pad "73" smd rect
			(at 2.02489 -18.2499)
			(size 1.54991 0.24994)
			(layers "F.Cu" "F.Mask" "F.Paste")
		)
		(pad "74" smd rect
			(at -2.02489 -18.2499)
			(size 1.54991 0.24994)
			(layers "F.Cu" "F.Mask" "F.Paste")
		)
		(pad "75" smd rect
			(at 2.02489 -18.75002)
			(size 1.54991 0.24994)
			(layers "F.Cu" "F.Mask" "F.Paste")
		)
		(pad "76" smd rect
			(at -2.02489 -18.75002)
			(size 1.54991 0.24994)
			(layers "F.Cu" "F.Mask" "F.Paste")
		)
		(pad "77" smd rect
			(at 2.02489 -19.2499)
			(size 1.54991 0.24994)
			(layers "F.Cu" "F.Mask" "F.Paste")
			(net "FPGA_TCK")
		)
		(pad "78" smd rect
			(at -2.02489 -19.2499)
			(size 1.54991 0.24994)
			(layers "F.Cu" "F.Mask" "F.Paste")
			(net "FPGA_TDI")
		)
		(pad "79" smd rect
			(at 2.02489 -19.75002)
			(size 1.54991 0.24994)
			(layers "F.Cu" "F.Mask" "F.Paste")
			(net "FPGA_TDO")
		)
		(pad "80" smd rect
			(at -2.02489 -19.75002)
			(size 1.54991 0.24994)
			(layers "F.Cu" "F.Mask" "F.Paste")
			(net "FPGA_TMS")
		)
		(pad "81" smd rect
			(at 0.01136 1.17626)
			(size 1.70002 1.35001)
			(layers "F.Cu" "F.Mask" "F.Paste")
		)
		(pad "82" thru_hole circle
			(at 0 0)
			(size 0.55016 0.55016)
			(drill 0.55016)
			(layers "*.Cu" "*.Mask")
			(remove_unused_layers no)
			(thermal_bridge_angle 90)
		)
		(pad "83" thru_hole circle
			(at 0 -19.99996)
			(size 0.55016 0.55016)
			(drill 0.55016)
			(layers "*.Cu" "*.Mask")
			(remove_unused_layers no)
			(thermal_bridge_angle 90)
		)
		(pad "84" smd rect
			(at 0.01136 -21.17374)
			(size 1.70002 1.35001)
			(layers "F.Cu" "F.Mask" "F.Paste")
		)
	)
	(footprint "Vault:FP-0603-L_1_6_0_2-W_0_8_0-MFG"
		(layer "F.Cu")
		(at 232.1261 121.2162)
		(property "Reference" "C80"
			(at 2.6286 0.126921 0)
			(unlocked yes)
			(layer "F.SilkS")
			(effects
				(font
					(size 0.762 0.762)
					(thickness 0.2286)
				)
			)
		)
		(property "Value" "10uF_16V_0603"
			(at -2.871951 8.95046 270)
			(unlocked yes)
			(layer "F.SilkS")
			(hide yes)
			(effects
				(font
					(size 0.762 0.762)
					(thickness 0.2286)
				)
			)
		)
		(sheetname "POWER")
		(sheetfile "POWER.kicad_sch")
		(duplicate_pad_numbers_are_jumpers no)
		(fp_line
			(start -0.9 -0.825)
			(end 0.9 -0.825)
			(stroke
				(width 0.2)
				(type solid)
			)
			(layer "F.SilkS")
		)
		(fp_line
			(start -0.9 0.825)
			(end 0.9 0.825)
			(stroke
				(width 0.2)
				(type solid)
			)
			(layer "F.SilkS")
		)
		(fp_line
			(start -1.15 -0.6)
			(end 1.15 -0.6)
			(stroke
				(width 0.2)
				(type solid)
			)
			(layer "F.CrtYd")
		)
		(fp_line
			(start -1.15 0.6)
			(end -1.15 -0.6)
			(stroke
				(width 0.2)
				(type solid)
			)
			(layer "F.CrtYd")
		)
		(fp_line
			(start -1.15 0.6)
			(end 1.15 0.6)
			(stroke
				(width 0.2)
				(type solid)
			)
			(layer "F.CrtYd")
		)
		(fp_line
			(start 1.15 0.6)
			(end 1.15 -0.6)
			(stroke
				(width 0.2)
				(type solid)
			)
			(layer "F.CrtYd")
		)
		(fp_line
			(start -1.15 -0.6)
			(end 1.15 -0.6)
			(stroke
				(width 0.2)
				(type solid)
			)
			(layer "F.Fab")
		)
		(fp_line
			(start -1.15 0.6)
			(end -1.15 -0.6)
			(stroke
				(width 0.2)
				(type solid)
			)
			(layer "F.Fab")
		)
		(fp_line
			(start -1.15 0.6)
			(end 1.15 0.6)
			(stroke
				(width 0.2)
				(type solid)
			)
			(layer "F.Fab")
		)
		(fp_line
			(start -0.5 0)
			(end 0.5 0)
			(stroke
				(width 0.1)
				(type solid)
			)
			(layer "F.Fab")
		)
		(fp_line
			(start 0 0.5)
			(end 0 -0.5)
			(stroke
				(width 0.1)
				(type solid)
			)
			(layer "F.Fab")
		)
		(fp_line
			(start 1.15 0.6)
			(end 1.15 -0.6)
			(stroke
				(width 0.2)
				(type solid)
			)
			(layer "F.Fab")
		)
		(fp_text user "${REFERENCE}"
			(at -0.00001 0.09602 360)
			(unlocked yes)
			(layer "F.Fab")
			(effects
				(font
					(face "Arial")
					(size 0.63 0.63)
					(thickness 0.1)
				)
				(justify left bottom)
			)
		)
		(pad "1" smd rect
			(at -0.7 0)
			(size 0.7 0.7)
			(layers "F.Cu" "F.Mask" "F.Paste")
			(net "+3.3V")
			(solder_mask_margin 0)
			(solder_paste_margin 0)
		)
		(pad "2" smd rect
			(at 0.7 0)
			(size 0.7 0.7)
			(layers "F.Cu" "F.Mask" "F.Paste")
			(net "GND")
			(solder_mask_margin 0)
			(solder_paste_margin 0)
		)
	)
	(footprint "Vault:RESC1005X40X25NL05T05"
		(layer "F.Cu")
		(at 222.6261 80.4162 180)
		(property "Reference" "R86"
			(at -2.4286 -0.326921 0)
			(unlocked yes)
			(layer "F.SilkS")
			(effects
				(font
					(size 0.762 0.762)
					(thickness 0.2286)
				)
			)
		)
		(property "Value" "27_1%_0402"
			(at -2.732271 7.37632 90)
			(unlocked yes)
			(layer "F.SilkS")
			(hide yes)
			(effects
				(font
					(size 0.762 0.762)
					(thickness 0.2286)
				)
			)
		)
		(sheetname "USBUart_DipSelects")
		(sheetfile "USBUart_DipSelects.kicad_sch")
		(duplicate_pad_numbers_are_jumpers no)
		(pad "1" smd rect
			(at -0.45 0 270)
			(size 0.55 0.55)
			(layers "F.Cu" "F.Mask" "F.Paste")
			(net "GND")
		)
		(pad "2" smd rect
			(at 0.45 0 270)
			(size 0.55 0.55)
			(layers "F.Cu" "F.Mask" "F.Paste")
			(net "NetR86_2")
		)
	)
	(footprint "Vault:RESC1005X40X25LL05T10"
		(layer "F.Cu")
		(at 129.1261 85.7162 -90)
		(property "Reference" "R107"
			(at 0.3286 -0.873069 270)
			(unlocked yes)
			(layer "F.SilkS")
			(effects
				(font
					(size 0.762 0.762)
					(thickness 0.2286)
				)
			)
		)
		(property "Value" "DNI_49.9_1%_0402"
			(at -2.579871 11.74373 180)
			(unlocked yes)
			(layer "F.SilkS")
			(hide yes)
			(effects
				(font
					(size 0.762 0.762)
					(thickness 0.2286)
				)
			)
		)
		(sheetname "USBUart_DipSelects")
		(sheetfile "USBUart_DipSelects.kicad_sch")
		(duplicate_pad_numbers_are_jumpers no)
		(pad "1" smd rect
			(at -0.375 0)
			(size 0.45 0.5)
			(layers "F.Cu" "F.Mask" "F.Paste")
			(net "FPGA_MAC_PPS_IN0-")
		)
		(pad "2" smd rect
			(at 0.375 0)
			(size 0.45 0.5)
			(layers "F.Cu" "F.Mask" "F.Paste")
			(net "FPGA_MAC_PPS_DIFF_IN0")
		)
	)
)
